# S9S_MB_2U (Grand Teton) — schematic netlist excerpt (pin names and nets, part order shuffled) for the footprints in the layout excerpt that follows; sources: Cadence DE-HDL packaged netlist, KiCad conversion of 03242023_DA0F0TMBIJ0_F0T_Motherboard_J_brd_V01_OCP.brd

U268  GL852GOHY60  GL852G-OHY60 IC  pkg QFN28_THXL  page 152
  DM0  = USB2_P0_R_DN
  DP0  = USB2_P0_R_DP
  DM1  = USB2_HUB_SWB_DN
  DP1  = USB2_HUB_SWB_DP
  AVDD(0)  = P3V3_AUX_USB_HUB
  DM2  = NC_USB_HUB_DM2
  DP2  = NC_USB_HUB_DP2
  RREF  = USB_HUB_RREF
  AVDD(1)  = P3V3_AUX_USB_HUB
  X1  = USB_HUB_XTAL_IN
  X2  = USB_HUB_XTAL_OUT
  DM3  = NC_USB_HUB_DM3
  DP3  = NC_USB_HUB_DP3
  AVDD(2)  = P3V3_AUX_USB_HUB
  DM4  = NC_USB_HUB_DM4
  DP4  = NC_USB_HUB_DP4
  \reset#\  = RST_USB_HUB_R_N
  \test||scl\  = USB_HUB_TEST
  \ovcur4#\  = USB_HUB_OVCUR4
  \ovcur3#\  = USB_HUB_OVCUR3
  DVDD  = USB_HUB_DVDD
  PSELF  = USB_HUB_PSELF
  PGANG  = USB_HUB_PGANG
  \ovcur2#||smd\  = USB_HUB_OVCUR2
  \ovcur1#||smc\  = USB_HUB_OVCUR1
  SDA  = NC_USB_HUB_SDA
  V5  = P3V3_AUX_USB_HUB
  V33  = P3V3_AUX_USB_HUB
  TH  = GND

(kicad_pcb
	(version 20260206)
	(generator "pcbnew")
	(generator_version "10.0")
	(general
		(thickness 1.6)
		(legacy_teardrops no)
	)
	(paper "A4")
	(title_block
		(title "03242023_DA0F0TMBIJ0_F0T_Motherboard_J_brd_V01_OCP.brd")
		(comment 1 "Grand Teton / footprint 3751 of 6105 (U268), pads 1-29 of 29")
	)
	(layers
		(0 "F.Cu" signal "TOP")
		(4 "In1.Cu" signal "GND")
		(6 "In2.Cu" signal "IN1")
		(8 "In3.Cu" signal "GND1")
		(10 "In4.Cu" signal "IN2")
		(12 "In5.Cu" signal "GND2")
		(14 "In6.Cu" signal "IN3")
		(16 "In7.Cu" signal "GND3")
		(18 "In8.Cu" signal "VCC")
		(20 "In9.Cu" signal "VCC1")
		(22 "In10.Cu" signal "GND4")
		(24 "In11.Cu" signal "IN4")
		(26 "In12.Cu" signal "GND5")
		(28 "In13.Cu" signal "IN5")
		(30 "In14.Cu" signal "GND6")
		(32 "In15.Cu" signal "IN6")
		(34 "In16.Cu" signal "GND7")
		(2 "B.Cu" signal "BOTTOM")
		(9 "F.Adhes" user "F.Adhesive")
		(11 "B.Adhes" user "B.Adhesive")
		(13 "F.Paste" user "Package Geometry/Pastemask Top")
		(15 "B.Paste" user "Package Geometry/Pastemask Bottom")
		(5 "F.SilkS" user "Ref Des/Silkscreen Top")
		(7 "B.SilkS" user "Ref Des/Silkscreen Bottom")
		(1 "F.Mask" user "Board Geometry/Soldermask Top")
		(3 "B.Mask" user "Board Geometry/Soldermask Bottom")
		(17 "Dwgs.User" user "User.Drawings")
		(19 "Cmts.User" user "User.Comments")
		(21 "Eco1.User" user "User.Eco1")
		(23 "Eco2.User" user "User.Eco2")
		(25 "Edge.Cuts" user "Board Geometry/Outline")
		(27 "Margin" user)
		(31 "F.CrtYd" user "Package Geometry/Place Bound Top")
		(29 "B.CrtYd" user "Package Geometry/Place Bound Bottom")
		(35 "F.Fab" user "Ref Des/Assembly Top")
		(33 "B.Fab" user "Ref Des/Assembly Bottom")
	)
	(footprint ""
		(layer "F.Cu")
		(at 14.064996 -99.136454 -90)
		(property "Reference" "U268"
			(at -3.321558 -3.514598 0)
			(unlocked yes)
			(layer "F.SilkS")
			(effects
				(font
					(size 0.7874 0.5842)
					(thickness 0.1524)
				)
				(justify left)
			)
		)
		(property "Value" ""
			(at 0 0 270)
			(layer "F.Fab")
			(effects
				(font
					(size 1.27 1.27)
				)
			)
		)
		(duplicate_pad_numbers_are_jumpers no)
		(pad "1" smd rect
			(at -2.412492 -1.500124)
			(size 0.254 0.7366)
			(layers "F.Cu" "F.Mask" "F.Paste")
			(net "USB2_P0_R_DN")
		)
		(pad "2" smd rect
			(at -2.412492 -0.999998)
			(size 0.254 0.7366)
			(layers "F.Cu" "F.Mask" "F.Paste")
			(net "USB2_P0_R_DP")
		)
		(pad "3" smd rect
			(at -2.412492 -0.499872)
			(size 0.254 0.7366)
			(layers "F.Cu" "F.Mask" "F.Paste")
			(net "USB2_HUB_SWB_DN")
		)
		(pad "4" smd rect
			(at -2.412492 0)
			(size 0.254 0.7366)
			(layers "F.Cu" "F.Mask" "F.Paste")
			(net "USB2_HUB_SWB_DP")
		)
		(pad "5" smd rect
			(at -2.412492 0.499872)
			(size 0.254 0.7366)
			(layers "F.Cu" "F.Mask" "F.Paste")
			(net "P3V3_AUX_USB_HUB")
		)
		(pad "6" smd rect
			(at -2.412492 0.999998)
			(size 0.254 0.7366)
			(layers "F.Cu" "F.Mask" "F.Paste")
			(net "NC_USB_HUB_DM2")
		)
		(pad "7" smd rect
			(at -2.412492 1.500124)
			(size 0.254 0.7366)
			(layers "F.Cu" "F.Mask" "F.Paste")
			(net "NC_USB_HUB_DP2")
		)
		(pad "8" smd rect
			(at -1.500124 2.412492 270)
			(size 0.254 0.7366)
			(layers "F.Cu" "F.Mask" "F.Paste")
			(net "USB_HUB_RREF")
		)
		(pad "9" smd rect
			(at -0.999998 2.412492 270)
			(size 0.254 0.7366)
			(layers "F.Cu" "F.Mask" "F.Paste")
			(net "P3V3_AUX_USB_HUB")
		)
		(pad "10" smd rect
			(at -0.499872 2.412492 270)
			(size 0.254 0.7366)
			(layers "F.Cu" "F.Mask" "F.Paste")
			(net "USB_HUB_XTAL_IN")
		)
		(pad "11" smd rect
			(at 0 2.412492 270)
			(size 0.254 0.7366)
			(layers "F.Cu" "F.Mask" "F.Paste")
			(net "USB_HUB_XTAL_OUT")
		)
		(pad "12" smd rect
			(at 0.499872 2.412492 270)
			(size 0.254 0.7366)
			(layers "F.Cu" "F.Mask" "F.Paste")
			(net "NC_USB_HUB_DM3")
		)
		(pad "13" smd rect
			(at 0.999998 2.412492 270)
			(size 0.254 0.7366)
			(layers "F.Cu" "F.Mask" "F.Paste")
			(net "NC_USB_HUB_DP3")
		)
		(pad "14" smd rect
			(at 1.500124 2.412492 270)
			(size 0.254 0.7366)
			(layers "F.Cu" "F.Mask" "F.Paste")
			(net "P3V3_AUX_USB_HUB")
		)
		(pad "15" smd rect
			(at 2.412492 1.500124)
			(size 0.254 0.7366)
			(layers "F.Cu" "F.Mask" "F.Paste")
			(net "NC_USB_HUB_DM4")
		)
		(pad "16" smd rect
			(at 2.412492 0.999998)
			(size 0.254 0.7366)
			(layers "F.Cu" "F.Mask" "F.Paste")
			(net "NC_USB_HUB_DP4")
		)
		(pad "17" smd rect
			(at 2.412492 0.499872)
			(size 0.254 0.7366)
			(layers "F.Cu" "F.Mask" "F.Paste")
			(net "RST_USB_HUB_R_N")
		)
		(pad "18" smd rect
			(at 2.412492 0)
			(size 0.254 0.7366)
			(layers "F.Cu" "F.Mask" "F.Paste")
			(net "USB_HUB_TEST")
		)
		(pad "19" smd rect
			(at 2.412492 -0.499872)
			(size 0.254 0.7366)
			(layers "F.Cu" "F.Mask" "F.Paste")
			(net "USB_HUB_OVCUR4")
		)
		(pad "20" smd rect
			(at 2.412492 -0.999998)
			(size 0.254 0.7366)
			(layers "F.Cu" "F.Mask" "F.Paste")
			(net "USB_HUB_OVCUR3")
		)
		(pad "21" smd rect
			(at 2.412492 -1.500124)
			(size 0.254 0.7366)
			(layers "F.Cu" "F.Mask" "F.Paste")
			(net "USB_HUB_DVDD")
		)
		(pad "22" smd rect
			(at 1.500124 -2.412492 270)
			(size 0.254 0.7366)
			(layers "F.Cu" "F.Mask" "F.Paste")
			(net "USB_HUB_PSELF")
		)
		(pad "23" smd rect
			(at 0.999998 -2.412492 270)
			(size 0.254 0.7366)
			(layers "F.Cu" "F.Mask" "F.Paste")
			(net "USB_HUB_PGANG")
		)
		(pad "24" smd rect
			(at 0.499872 -2.412492 270)
			(size 0.254 0.7366)
			(layers "F.Cu" "F.Mask" "F.Paste")
			(net "USB_HUB_OVCUR2")
		)
		(pad "25" smd rect
			(at 0 -2.412492 270)
			(size 0.254 0.7366)
			(layers "F.Cu" "F.Mask" "F.Paste")
			(net "USB_HUB_OVCUR1")
		)
		(pad "26" smd rect
			(at -0.499872 -2.412492 270)
			(size 0.254 0.7366)
			(layers "F.Cu" "F.Mask" "F.Paste")
			(net "NC_USB_HUB_SDA")
		)
		(pad "27" smd rect
			(at -0.999998 -2.412492 270)
			(size 0.254 0.7366)
			(layers "F.Cu" "F.Mask" "F.Paste")
			(net "P3V3_AUX_USB_HUB")
		)
		(pad "28" smd rect
			(at -1.500124 -2.412492 270)
			(size 0.254 0.7366)
			(layers "F.Cu" "F.Mask" "F.Paste")
			(net "P3V3_AUX_USB_HUB")
		)
		(pad "TH" smd rect
			(at 0 0 270)
			(size 3.556 3.556)
			(layers "F.Cu" "F.Mask" "F.Paste")
			(net "GND")
		)
	)
)
